(kicad_pcb
	(version 20241229)
	(generator "pcbnew")
	(generator_version "9.0")
	(general
		(thickness 1.63)
		(legacy_teardrops no)
	)
	(paper "A4")
	(title_block
		(title "CM4 Baseboard")
		(date "2026-01-05")
		(rev "1.1.1")
		(company "Antmicro Ltd")
		(comment 1 "www.antmicro.com")
		(comment 9 "footprints 93-97 of 506")
	)
	(layers
		(0 "F.Cu" signal)
		(4 "In1.Cu" power)
		(6 "In2.Cu" power)
		(8 "In3.Cu" signal)
		(10 "In4.Cu" signal)
		(2 "B.Cu" signal)
		(9 "F.Adhes" user "F.Adhesive")
		(11 "B.Adhes" user "B.Adhesive")
		(13 "F.Paste" user)
		(15 "B.Paste" user)
		(5 "F.SilkS" user "F.Silkscreen")
		(7 "B.SilkS" user "B.Silkscreen")
		(1 "F.Mask" user)
		(3 "B.Mask" user)
		(17 "Dwgs.User" user "User.Drawings")
		(19 "Cmts.User" user "User.Comments")
		(21 "Eco1.User" user "User.Eco1")
		(23 "Eco2.User" user "User.Eco2")
		(25 "Edge.Cuts" user)
		(27 "Margin" user)
		(31 "F.CrtYd" user "F.Courtyard")
		(29 "B.CrtYd" user "B.Courtyard")
		(35 "F.Fab" user)
		(33 "B.Fab" user)
	)
	(footprint "antmicro-footprints:R_0402_1005Metric"
		(layer "F.Cu")
		(at 46.542962 131.7165)
		(descr "Resistor SMD 0402")
		(tags "resistor SMD 0402")
		(property "Reference" "R401"
			(at -3.975 0.475 0)
			(layer "F.SilkS")
			(effects
				(font
					(size 0.7 0.7)
					(thickness 0.15)
				)
				(justify left bottom)
			)
		)
		(property "Value" "R_1k3_0402"
			(at -1.011843 1.772047 0)
			(layer "F.Fab")
			(effects
				(font
					(size 0.7 0.7)
					(thickness 0.15)
				)
				(justify left bottom)
			)
		)
		(property "Datasheet" "https://www.bourns.com/docs/product-datasheets/cr.pdf"
			(at 0 0 0)
			(layer "F.Fab")
			(hide yes)
			(effects
				(font
					(size 1.27 1.27)
					(thickness 0.15)
				)
			)
		)
		(property "Manufacturer" "Bourns"
			(at 0 0 0)
			(unlocked yes)
			(layer "F.Fab")
			(hide yes)
			(effects
				(font
					(size 1 1)
					(thickness 0.15)
				)
			)
		)
		(property "MPN" "CR0402-FX-1301GLF"
			(at 0 0 0)
			(unlocked yes)
			(layer "F.Fab")
			(hide yes)
			(effects
				(font
					(size 1 1)
					(thickness 0.15)
				)
			)
		)
		(property "Val" "1k3"
			(at 0 0 0)
			(unlocked yes)
			(layer "F.Fab")
			(hide yes)
			(effects
				(font
					(size 1 1)
					(thickness 0.15)
				)
			)
		)
		(property "License" "Apache-2.0"
			(at 0 0 0)
			(unlocked yes)
			(layer "F.Fab")
			(hide yes)
			(effects
				(font
					(size 1 1)
					(thickness 0.15)
				)
			)
		)
		(property "Author" "Antmicro"
			(at 0 0 0)
			(unlocked yes)
			(layer "F.Fab")
			(hide yes)
			(effects
				(font
					(size 1 1)
					(thickness 0.15)
				)
			)
		)
		(property "Tolerance" "1%"
			(at 0 0 0)
			(unlocked yes)
			(layer "F.Fab")
			(hide yes)
			(effects
				(font
					(size 1 1)
					(thickness 0.15)
				)
			)
		)
		(sheetname "/Ethernet/")
		(sheetfile "ethernet.kicad_sch")
		(attr smd)
		(fp_rect
			(start -0.925 -0.47)
			(end 0.925 0.47)
			(stroke
				(width 0.05)
				(type default)
			)
			(fill no)
			(layer "F.CrtYd")
		)
		(fp_rect
			(start -0.5 -0.25)
			(end 0.5 0.25)
			(stroke
				(width 0.15)
				(type solid)
			)
			(fill no)
			(layer "F.Fab")
		)
		(fp_text user "Author: Antmicro"
			(at -0.95 4.169 0)
			(layer "F.Fab")
			(effects
				(font
					(size 0.7 0.7)
					(thickness 0.15)
				)
				(justify left bottom)
			)
		)
		(fp_text user "License: Apache-2.0"
			(at -0.95 5.169 0)
			(layer "F.Fab")
			(effects
				(font
					(size 0.7 0.7)
					(thickness 0.15)
				)
				(justify left bottom)
			)
		)
		(fp_text user "${REFERENCE}"
			(at -0.95 3.168 0)
			(layer "F.Fab")
			(effects
				(font
					(size 0.7 0.7)
					(thickness 0.15)
				)
				(justify left bottom)
			)
		)
		(pad "1" smd roundrect
			(at -0.48 0)
			(size 0.59 0.64)
			(layers "F.Cu" "F.Mask" "F.Paste")
			(roundrect_rratio 0.25)
			(net 90 "/Ethernet/VSS")
			(pintype "passive")
		)
		(pad "2" smd roundrect
			(at 0.48 0)
			(size 0.59 0.64)
			(layers "F.Cu" "F.Mask" "F.Paste")
			(roundrect_rratio 0.25)
			(net 356 "/Ethernet/AMPS_CTL")
			(pintype "passive")
		)
	)
	(footprint "antmicro-footprints:TP_SMD_0.75mm"
		(layer "F.Cu")
		(at 134.787962 156.1165 -90)
		(property "Reference" "TP601"
			(at -3.8415 -1.062038 90)
			(layer "F.SilkS")
			(effects
				(font
					(size 0.7 0.7)
					(thickness 0.15)
				)
				(justify right bottom)
			)
		)
		(property "Value" "TP_0.75mm_SMD"
			(at 0 1.2 90)
			(layer "F.Fab")
			(effects
				(font
					(size 0.7 0.7)
					(thickness 0.15)
				)
				(justify right bottom)
			)
		)
		(property "MPN" ""
			(at 0 0 270)
			(unlocked yes)
			(layer "F.Fab")
			(hide yes)
			(effects
				(font
					(size 1 1)
					(thickness 0.15)
				)
			)
		)
		(property "Manufacturer" ""
			(at 0 0 270)
			(unlocked yes)
			(layer "F.Fab")
			(hide yes)
			(effects
				(font
					(size 1 1)
					(thickness 0.15)
				)
			)
		)
		(property "Author" "Antmicro"
			(at 0 0 270)
			(unlocked yes)
			(layer "F.Fab")
			(hide yes)
			(effects
				(font
					(size 1 1)
					(thickness 0.15)
				)
			)
		)
		(property "License" "Apache-2.0"
			(at 0 0 270)
			(unlocked yes)
			(layer "F.Fab")
			(hide yes)
			(effects
				(font
					(size 1 1)
					(thickness 0.15)
				)
			)
		)
		(sheetname "/CSI/")
		(sheetfile "csi.kicad_sch")
		(attr exclude_from_pos_files exclude_from_bom)
		(fp_circle
			(center 0 0)
			(end 0.475 0)
			(stroke
				(width 0.05)
				(type default)
			)
			(fill no)
			(layer "F.CrtYd")
		)
		(fp_text user "Author: Antmicro"
			(at -0.4 3.901 270)
			(layer "F.Fab")
			(effects
				(font
					(size 0.7 0.7)
					(thickness 0.15)
				)
				(justify left bottom)
			)
		)
		(fp_text user "${REFERENCE}"
			(at -0.4 2.7 270)
			(layer "F.Fab")
			(effects
				(font
					(size 0.7 0.7)
					(thickness 0.15)
				)
				(justify left bottom)
			)
		)
		(fp_text user "License: Apache-2.0"
			(at -0.4 5.101 270)
			(layer "F.Fab")
			(effects
				(font
					(size 0.7 0.7)
					(thickness 0.15)
				)
				(justify left bottom)
			)
		)
		(pad "1" smd circle
			(at 0 0 270)
			(size 0.75 0.75)
			(layers "F.Cu" "F.Mask")
			(net 370 "Net-(U601-FLG)")
			(pinfunction "1")
			(pintype "passive")
		)
	)
	(footprint "antmicro-footprints:TP_SMD_0.75mm"
		(layer "F.Cu")
		(at 74.2 154.99)
		(property "Reference" "TP302"
			(at -6.8392 0.87 0)
			(layer "F.SilkS")
			(effects
				(font
					(size 0.7 0.7)
					(thickness 0.15)
				)
				(justify left bottom)
			)
		)
		(property "Value" "TP_0.75mm_SMD"
			(at 0 1.2 0)
			(layer "F.Fab")
			(effects
				(font
					(size 0.7 0.7)
					(thickness 0.15)
				)
				(justify left bottom)
			)
		)
		(property "MPN" ""
			(at 0 0 0)
			(unlocked yes)
			(layer "F.Fab")
			(hide yes)
			(effects
				(font
					(size 1 1)
					(thickness 0.15)
				)
			)
		)
		(property "Manufacturer" ""
			(at 0 0 0)
			(unlocked yes)
			(layer "F.Fab")
			(hide yes)
			(effects
				(font
					(size 1 1)
					(thickness 0.15)
				)
			)
		)
		(property "Author" "Antmicro"
			(at 0 0 0)
			(unlocked yes)
			(layer "F.Fab")
			(hide yes)
			(effects
				(font
					(size 1 1)
					(thickness 0.15)
				)
			)
		)
		(property "License" "Apache-2.0"
			(at 0 0 0)
			(unlocked yes)
			(layer "F.Fab")
			(hide yes)
			(effects
				(font
					(size 1 1)
					(thickness 0.15)
				)
			)
		)
		(sheetname "/Supply/")
		(sheetfile "supply.kicad_sch")
		(attr exclude_from_pos_files exclude_from_bom)
		(fp_circle
			(center 0 0)
			(end 0.475 0)
			(stroke
				(width 0.05)
				(type default)
			)
			(fill no)
			(layer "F.CrtYd")
		)
		(fp_text user "${REFERENCE}"
			(at -0.4 2.7 0)
			(layer "F.Fab")
			(effects
				(font
					(size 0.7 0.7)
					(thickness 0.15)
				)
				(justify left bottom)
			)
		)
		(fp_text user "License: Apache-2.0"
			(at -0.4 5.101 0)
			(layer "F.Fab")
			(effects
				(font
					(size 0.7 0.7)
					(thickness 0.15)
				)
				(justify left bottom)
			)
		)
		(fp_text user "Author: Antmicro"
			(at -0.4 3.901 0)
			(layer "F.Fab")
			(effects
				(font
					(size 0.7 0.7)
					(thickness 0.15)
				)
				(justify left bottom)
			)
		)
		(pad "1" smd circle
			(at 0 0)
			(size 0.75 0.75)
			(layers "F.Cu" "F.Mask")
			(net 3 "GND")
			(pinfunction "1")
			(pintype "passive")
		)
	)
	(footprint "antmicro-footprints:SOT-523"
		(layer "F.Cu")
		(at 82.117962 169.5415 90)
		(property "Reference" "Q209"
			(at -0.735 1.24 180)
			(layer "F.SilkS")
			(effects
				(font
					(size 0.7 0.7)
					(thickness 0.15)
				)
				(justify left bottom)
			)
		)
		(property "Value" "PJE138K"
			(at 0.1 1.824 90)
			(layer "F.Fab")
			(effects
				(font
					(size 0.7 0.7)
					(thickness 0.15)
				)
				(justify left bottom)
			)
		)
		(property "Datasheet" "https://www.mouser.com/datasheet/2/1057/PJE138K-1876698.pdf"
			(at 0 0 90)
			(layer "F.Fab")
			(hide yes)
			(effects
				(font
					(size 1.27 1.27)
					(thickness 0.15)
				)
			)
		)
		(property "MPN" "PJE138K_R1_00001"
			(at 0 0 90)
			(unlocked yes)
			(layer "F.Fab")
			(hide yes)
			(effects
				(font
					(size 1 1)
					(thickness 0.15)
				)
			)
		)
		(property "Manufacturer" "PANJIT"
			(at 0 0 90)
			(unlocked yes)
			(layer "F.Fab")
			(hide yes)
			(effects
				(font
					(size 1 1)
					(thickness 0.15)
				)
			)
		)
		(property "Author" "Antmicro"
			(at 0 0 90)
			(unlocked yes)
			(layer "F.Fab")
			(hide yes)
			(effects
				(font
					(size 1 1)
					(thickness 0.15)
				)
			)
		)
		(property "License" "Apache-2.0"
			(at 0 0 90)
			(unlocked yes)
			(layer "F.Fab")
			(hide yes)
			(effects
				(font
					(size 1 1)
					(thickness 0.15)
				)
			)
		)
		(sheetname "/Compute module/")
		(sheetfile "compute-module.kicad_sch")
		(attr smd)
		(fp_line
			(start -0.277 -0.551)
			(end -0.277 -0.75)
			(stroke
				(width 0.15)
				(type solid)
			)
			(layer "F.SilkS")
		)
		(fp_line
			(start -0.725 -0.551)
			(end -0.277 -0.551)
			(stroke
				(width 0.15)
				(type solid)
			)
			(layer "F.SilkS")
		)
		(fp_line
			(start -0.927 -0.351)
			(end -0.725 -0.551)
			(stroke
				(width 0.15)
				(type solid)
			)
			(layer "F.SilkS")
		)
		(fp_line
			(start -0.927 -0.051)
			(end -0.927 -0.351)
			(stroke
				(width 0.15)
				(type solid)
			)
			(layer "F.SilkS")
		)
		(fp_circle
			(center -0.9652 0.9652)
			(end -0.9152 0.9652)
			(stroke
				(width 0.15)
				(type solid)
			)
			(fill yes)
			(layer "F.SilkS")
		)
		(fp_line
			(start 1.1 -1.16)
			(end 1.1 1.15)
			(stroke
				(width 0.05)
				(type solid)
			)
			(layer "F.CrtYd")
		)
		(fp_line
			(start -1.12 -1.16)
			(end 1.1 -1.16)
			(stroke
				(width 0.05)
				(type solid)
			)
			(layer "F.CrtYd")
		)
		(fp_line
			(start -1.12 -1.16)
			(end -1.12 1.15)
			(stroke
				(width 0.05)
				(type solid)
			)
			(layer "F.CrtYd")
		)
		(fp_line
			(start -1.12 1.15)
			(end 1.1 1.15)
			(stroke
				(width 0.05)
				(type solid)
			)
			(layer "F.CrtYd")
		)
		(fp_line
			(start 0.8 -0.425)
			(end -0.652 -0.425)
			(stroke
				(width 0.15)
				(type solid)
			)
			(layer "F.Fab")
		)
		(fp_line
			(start 0.8 -0.425)
			(end 0.8 0.424)
			(stroke
				(width 0.15)
				(type solid)
			)
			(layer "F.Fab")
		)
		(fp_line
			(start -0.652 -0.425)
			(end -0.802 -0.276)
			(stroke
				(width 0.15)
				(type solid)
			)
			(layer "F.Fab")
		)
		(fp_line
			(start -0.802 -0.276)
			(end -0.802 0.424)
			(stroke
				(width 0.15)
				(type solid)
			)
			(layer "F.Fab")
		)
		(fp_line
			(start 0.8 0.424)
			(end -0.802 0.424)
			(stroke
				(width 0.15)
				(type solid)
			)
			(layer "F.Fab")
		)
		(fp_circle
			(center -0.9652 0.9652)
			(end -0.9144 0.9652)
			(stroke
				(width 0.15)
				(type solid)
			)
			(fill no)
			(layer "F.Fab")
		)
		(fp_text user "License: Apache-2.0"
			(at -1.12 5.024 90)
			(layer "F.Fab")
			(effects
				(font
					(size 0.7 0.7)
					(thickness 0.15)
				)
				(justify left bottom)
			)
		)
		(fp_text user "Author: Antmicro"
			(at -1.12 6.224 90)
			(layer "F.Fab")
			(effects
				(font
					(size 0.7 0.7)
					(thickness 0.15)
				)
				(justify left bottom)
			)
		)
		(fp_text user "${REFERENCE}"
			(at -1.12 3.824 90)
			(layer "F.Fab")
			(effects
				(font
					(size 0.7 0.7)
					(thickness 0.15)
				)
				(justify left bottom)
			)
		)
		(pad "1" smd rect
			(at -0.5 0.65 90)
			(size 0.4 0.51)
			(layers "F.Cu" "F.Mask" "F.Paste")
			(net 4 "Net-(D204-A)")
			(pinfunction "G")
			(pintype "input")
		)
		(pad "2" smd rect
			(at 0.498 0.65 90)
			(size 0.4 0.51)
			(layers "F.Cu" "F.Mask" "F.Paste")
			(net 249 "/Compute module/RUN_PG")
			(pinfunction "S")
			(pintype "passive")
		)
		(pad "3" smd rect
			(at 0 -0.652 90)
			(size 0.4 0.51)
			(layers "F.Cu" "F.Mask" "F.Paste")
			(net 330 "Net-(Q209-D)")
			(pinfunction "D")
			(pintype "passive")
		)
	)
	(footprint "antmicro-footprints:Compute-Module-4_H1.5mm"
		(locked yes)
		(layer "F.Cu")
		(at 76.460961 157.754 90)
		(property "Reference" "M201"
			(at -0.3102 0.780439 90)
			(layer "F.SilkS")
			(hide yes)
			(effects
				(font
					(size 0.7 0.7)
					(thickness 0.15)
				)
				(justify left bottom)
			)
		)
		(property "Value" "Compute-Module-4_H1.5mm"
			(at 0 -0.5 90)
			(layer "F.Fab")
			(effects
				(font
					(size 0.7 0.7)
					(thickness 0.15)
				)
				(justify left bottom)
			)
		)
		(property "Datasheet" "https://datasheets.raspberrypi.com/cm4/cm4-datasheet.pdf"
			(at 0 0 90)
			(layer "F.Fab")
			(hide yes)
			(effects
				(font
					(size 1.27 1.27)
					(thickness 0.15)
				)
			)
		)
		(property "Manufacturer" "Raspberry Pi"
			(at 0 0 90)
			(unlocked yes)
			(layer "F.Fab")
			(hide yes)
			(effects
				(font
					(size 1 1)
					(thickness 0.15)
				)
			)
		)
		(property "MPN" "SC0294"
			(at 0 0 90)
			(unlocked yes)
			(layer "F.Fab")
			(hide yes)
			(effects
				(font
					(size 1 1)
					(thickness 0.15)
				)
			)
		)
		(property "Author" "Antmicro"
			(at 0 0 90)
			(unlocked yes)
			(layer "F.Fab")
			(hide yes)
			(effects
				(font
					(size 1 1)
					(thickness 0.15)
				)
			)
		)
		(property "License" "Apache-2.0"
			(at 0 0 90)
			(unlocked yes)
			(layer "F.Fab")
			(hide yes)
			(effects
				(font
					(size 1 1)
					(thickness 0.15)
				)
			)
		)
		(sheetname "/Compute module/")
		(sheetfile "compute-module.kicad_sch")
		(attr exclude_from_pos_files exclude_from_bom dnp)
		(fp_text user "99"
			(at -8.401 35.7 90)
			(layer "F.Fab")
			(effects
				(font
					(size 0.7 0.7)
					(thickness 0.15)
				)
				(justify left bottom)
			)
		)
		(fp_text user "100"
			(at -8.5 5.7 90)
			(layer "F.Fab")
			(effects
				(font
					(size 0.7 0.7)
					(thickness 0.15)
				)
				(justify left bottom)
			)
		)
		(fp_text user "99"
			(at -8.5 1.699 90)
			(layer "F.Fab")
			(effects
				(font
					(size 0.7 0.7)
					(thickness 0.15)
				)
				(justify left bottom)
			)
		)
		(fp_text user "Author: Antmicro"
			(at -22 43.77 90)
			(layer "F.Fab")
			(effects
				(font
					(size 0.7 0.7)
					(thickness 0.15)
				)
				(justify left bottom)
			)
		)
		(fp_text user "2"
			(at 14.599 39.6 90)
			(layer "F.Fab")
			(effects
				(font
					(size 0.7 0.7)
					(thickness 0.15)
				)
				(justify left bottom)
			)
		)
		(fp_text user "License: Apache-2.0"
			(at -22 44.97 90)
			(layer "F.Fab")
			(effects
				(font
					(size 0.7 0.7)
					(thickness 0.15)
				)
				(justify left bottom)
			)
		)
		(fp_text user "${REFERENCE}"
			(at -22 42.569 90)
			(layer "F.Fab")
			(effects
				(font
					(size 0.7 0.7)
					(thickness 0.15)
				)
				(justify left bottom)
			)
		)
		(fp_text user "1"
			(at 14.599 35.6 90)
			(layer "F.Fab")
			(effects
				(font
					(size 0.7 0.7)
					(thickness 0.15)
				)
				(justify left bottom)
			)
		)
		(fp_text user "100"
			(at -8.401 39.7 90)
			(layer "F.Fab")
			(effects
				(font
					(size 0.7 0.7)
					(thickness 0.15)
				)
				(justify left bottom)
			)
		)
		(fp_text user "1"
			(at 14.499 1.6 90)
			(layer "F.Fab")
			(effects
				(font
					(size 0.7 0.7)
					(thickness 0.15)
				)
				(justify left bottom)
			)
		)
		(fp_text user "2"
			(at 14.499 5.599 90)
			(layer "F.Fab")
			(effects
				(font
					(size 0.7 0.7)
					(thickness 0.15)
				)
				(justify left bottom)
			)
		)
	)
)
